# BASEBOARD_FAB2 (Tioga Pass) — schematic netlist excerpt (pin names and nets, part order shuffled) for the footprints in the layout excerpt that follows; sources: Cadence DE-HDL packaged netlist, KiCad conversion of Wiwynn_Tioga_Pass_MB.brd

C7U2  CAP_A  47UF 4V 20% X5R  pkg 0603V  page 225 : A = PVDDQ_GHJ ; B = GND
R9T9  RES  4.75K 1% CHIP  pkg 0402  page 181 : A = P12V_PSU ; B = FM_MATED_IN_N
CR9P2  DIODE  BAT54WS IC  pkg SMLF  page 200 : C = FM_UV_ADR_TRIGGER_N ; A = FM_DISABLE_FAN_N

(kicad_pcb
	(version 20260206)
	(generator "pcbnew")
	(generator_version "10.0")
	(general
		(thickness 1.6)
		(legacy_teardrops no)
	)
	(paper "A4")
	(title_block
		(title "Wiwynn_Tioga_Pass_MB.brd")
		(comment 1 "Tioga Pass / footprints 3083-3085 of 4770")
	)
	(layers
		(0 "F.Cu" signal "TOP")
		(4 "In1.Cu" signal "L2GND")
		(6 "In2.Cu" signal "L3")
		(8 "In3.Cu" signal "L4GND")
		(10 "In4.Cu" signal "L5")
		(12 "In5.Cu" signal "L6GND")
		(14 "In6.Cu" signal "L7VCC")
		(16 "In7.Cu" signal "L8VCC")
		(18 "In8.Cu" signal "L9GND")
		(20 "In9.Cu" signal "L10")
		(22 "In10.Cu" signal "L11GND")
		(24 "In11.Cu" signal "L12")
		(26 "In12.Cu" signal "L13GND")
		(2 "B.Cu" signal "BOTTOM")
		(9 "F.Adhes" user "F.Adhesive")
		(11 "B.Adhes" user "B.Adhesive")
		(13 "F.Paste" user "Package Geometry/Pastemask Top")
		(15 "B.Paste" user "Package Geometry/Pastemask Bottom")
		(5 "F.SilkS" user "Ref Des/Silkscreen Top")
		(7 "B.SilkS" user "Ref Des/Silkscreen Bottom")
		(1 "F.Mask" user "Board Geometry/Soldermask Top")
		(3 "B.Mask" user "Board Geometry/Soldermask Bottom")
		(17 "Dwgs.User" user "User.Drawings")
		(19 "Cmts.User" user "User.Comments")
		(21 "Eco1.User" user "User.Eco1")
		(23 "Eco2.User" user "User.Eco2")
		(25 "Edge.Cuts" user "Board Geometry/Outline")
		(27 "Margin" user)
		(31 "F.CrtYd" user "Package Geometry/Place Bound Top")
		(29 "B.CrtYd" user "Package Geometry/Place Bound Bottom")
		(35 "F.Fab" user "Ref Des/Assembly Top")
		(33 "B.Fab" user "Ref Des/Assembly Bottom")
	)
	(footprint ""
		(layer "B.Cu")
		(at 26.0096 -30.988)
		(property "Reference" "R9T9"
			(at 0 0 0)
			(layer "B.SilkS")
			(hide yes)
			(effects
				(font
					(size 1.27 1.27)
				)
				(justify mirror)
			)
		)
		(property "Value" ""
			(at 0 0 0)
			(layer "B.Fab")
			(effects
				(font
					(size 1.27 1.27)
				)
				(justify mirror)
			)
		)
		(duplicate_pad_numbers_are_jumpers no)
		(fp_rect
			(start -0.2794 0.9906)
			(end 0.2794 -0.1016)
			(stroke
				(width 0)
				(type default)
			)
			(fill no)
			(layer "B.CrtYd")
		)
		(fp_line
			(start -0.2794 -0.1016)
			(end 0.2794 -0.1016)
			(stroke
				(width 0.1)
				(type default)
			)
			(layer "B.Fab")
		)
		(fp_line
			(start -0.2794 0.9906)
			(end -0.2794 -0.1016)
			(stroke
				(width 0.1)
				(type default)
			)
			(layer "B.Fab")
		)
		(fp_line
			(start 0.2794 -0.1016)
			(end 0.2794 0.9906)
			(stroke
				(width 0.1)
				(type default)
			)
			(layer "B.Fab")
		)
		(fp_line
			(start 0.2794 0.9906)
			(end -0.2794 0.9906)
			(stroke
				(width 0.1)
				(type default)
			)
			(layer "B.Fab")
		)
		(pad "1" smd rect
			(at 0 0 180)
			(size 0.508 0.508)
			(layers "B.Cu" "B.Mask" "B.Paste")
			(net "P12V_PSU")
		)
		(pad "2" smd rect
			(at 0 0.889 180)
			(size 0.508 0.508)
			(layers "B.Cu" "B.Mask" "B.Paste")
			(net "FM_MATED_IN_N")
		)
		(zone
			(layer "B.Cu")
			(hatch none 0.5)
			(connect_pads
				(clearance 0)
			)
			(min_thickness 0.25)
			(keepout
				(tracks not_allowed)
				(vias allowed)
				(pads allowed)
				(copperpour not_allowed)
				(footprints allowed)
			)
			(placement
				(enabled no)
				(sheetname "")
			)
			(fill
				(thermal_gap 0.5)
				(thermal_bridge_width 0.5)
				(island_removal_mode 0)
			)
			(polygon
				(pts
					(xy 25.7556 -30.353) (xy 26.2636 -30.353) (xy 26.2636 -30.734) (xy 25.7556 -30.734)
				)
			)
		)
		(zone
			(layer "B.Cu")
			(hatch none 0.5)
			(connect_pads
				(clearance 0)
			)
			(min_thickness 0.25)
			(keepout
				(tracks allowed)
				(vias not_allowed)
				(pads allowed)
				(copperpour not_allowed)
				(footprints allowed)
			)
			(placement
				(enabled no)
				(sheetname "")
			)
			(fill
				(thermal_gap 0.5)
				(thermal_bridge_width 0.5)
				(island_removal_mode 0)
			)
			(polygon
				(pts
					(xy 25.7556 -30.353) (xy 26.2636 -30.353) (xy 26.2636 -30.734) (xy 25.7556 -30.734)
				)
			)
		)
	)
	(footprint ""
		(layer "B.Cu")
		(at 24.1046 -84.5312 90)
		(property "Reference" "CR9P2"
			(at 0 0 90)
			(layer "B.SilkS")
			(hide yes)
			(effects
				(font
					(size 1.27 1.27)
				)
				(justify mirror)
			)
		)
		(property "Value" ""
			(at 0 0 90)
			(layer "B.Fab")
			(effects
				(font
					(size 1.27 1.27)
				)
				(justify mirror)
			)
		)
		(duplicate_pad_numbers_are_jumpers no)
		(fp_line
			(start -0.623062 -0.352806)
			(end -0.623062 0.770636)
			(stroke
				(width 0.1524)
				(type default)
			)
			(layer "B.SilkS")
		)
		(fp_line
			(start -0.623062 0.770636)
			(end -1.103884 1.603502)
			(stroke
				(width 0.1524)
				(type default)
			)
			(layer "B.SilkS")
		)
		(fp_line
			(start -1.103884 0.770636)
			(end -0.14224 0.770636)
			(stroke
				(width 0.1524)
				(type default)
			)
			(layer "B.SilkS")
		)
		(fp_line
			(start -0.14224 1.603502)
			(end -0.623062 0.770636)
			(stroke
				(width 0.1524)
				(type default)
			)
			(layer "B.SilkS")
		)
		(fp_line
			(start -0.623062 1.603502)
			(end -0.14224 1.603502)
			(stroke
				(width 0.1524)
				(type default)
			)
			(layer "B.SilkS")
		)
		(fp_line
			(start -1.103884 1.603502)
			(end -0.623062 1.603502)
			(stroke
				(width 0.1524)
				(type default)
			)
			(layer "B.SilkS")
		)
		(fp_line
			(start -0.623062 2.515108)
			(end -0.623062 1.603502)
			(stroke
				(width 0.1524)
				(type default)
			)
			(layer "B.SilkS")
		)
		(fp_poly
			(pts
				(xy 0.67437 0.24384) (xy 0.67437 2.04216) (xy -0.67437 2.04216) (xy -0.67437 0.24384)
			)
			(stroke
				(width 0)
				(type default)
			)
			(fill no)
			(layer "B.CrtYd")
		)
		(fp_line
			(start 0.67437 0.24384)
			(end 0.67437 2.04216)
			(stroke
				(width 0.1)
				(type default)
			)
			(layer "B.Fab")
		)
		(fp_line
			(start -0.67437 0.24384)
			(end 0.67437 0.24384)
			(stroke
				(width 0.1)
				(type default)
			)
			(layer "B.Fab")
		)
		(fp_line
			(start -0.623062 0.770636)
			(end -0.623062 -0.352806)
			(stroke
				(width 0.1)
				(type default)
			)
			(layer "B.Fab")
		)
		(fp_line
			(start -0.623062 0.770636)
			(end -1.103884 1.603502)
			(stroke
				(width 0.1)
				(type default)
			)
			(layer "B.Fab")
		)
		(fp_line
			(start -1.103884 0.770636)
			(end -0.14224 0.770636)
			(stroke
				(width 0.1)
				(type default)
			)
			(layer "B.Fab")
		)
		(fp_line
			(start -0.14224 1.603502)
			(end -0.623062 0.770636)
			(stroke
				(width 0.1)
				(type default)
			)
			(layer "B.Fab")
		)
		(fp_line
			(start -0.623062 1.603502)
			(end -0.623062 2.515108)
			(stroke
				(width 0.1)
				(type default)
			)
			(layer "B.Fab")
		)
		(fp_line
			(start -1.103884 1.603502)
			(end -0.14224 1.603502)
			(stroke
				(width 0.1)
				(type default)
			)
			(layer "B.Fab")
		)
		(fp_line
			(start 0.67437 2.04216)
			(end -0.67437 2.04216)
			(stroke
				(width 0.1)
				(type default)
			)
			(layer "B.Fab")
		)
		(fp_line
			(start -0.67437 2.04216)
			(end -0.67437 0.24384)
			(stroke
				(width 0.1)
				(type default)
			)
			(layer "B.Fab")
		)
		(pad "1" smd rect
			(at 0 0 270)
			(size 0.4064 1.016)
			(layers "B.Cu" "B.Mask" "B.Paste")
			(net "FM_UV_ADR_TRIGGER_N")
		)
		(pad "2" smd rect
			(at 0 2.286 270)
			(size 0.4064 1.016)
			(layers "B.Cu" "B.Mask" "B.Paste")
			(net "FM_DISABLE_FAN_N")
		)
	)
	(footprint ""
		(layer "B.Cu")
		(at 107.8611 -8.1534 90)
		(property "Reference" "C7U2"
			(at -1.848866 0.752348 90)
			(unlocked yes)
			(layer "B.SilkS")
			(effects
				(font
					(size 1.27 0.9652)
					(thickness 0.1524)
				)
				(justify mirror)
			)
		)
		(property "Value" ""
			(at 0 0 90)
			(layer "B.Fab")
			(effects
				(font
					(size 1.27 1.27)
				)
				(justify mirror)
			)
		)
		(duplicate_pad_numbers_are_jumpers no)
		(fp_rect
			(start 0.500126 1.598422)
			(end -0.500126 -0.201422)
			(stroke
				(width 0)
				(type default)
			)
			(fill no)
			(layer "B.CrtYd")
		)
		(fp_line
			(start 0.500126 -0.201422)
			(end -0.500126 -0.201422)
			(stroke
				(width 0.1)
				(type default)
			)
			(layer "B.Fab")
		)
		(fp_line
			(start -0.500126 -0.201422)
			(end -0.500126 1.598422)
			(stroke
				(width 0.1)
				(type default)
			)
			(layer "B.Fab")
		)
		(fp_line
			(start 0.500126 1.598422)
			(end 0.500126 -0.201422)
			(stroke
				(width 0.1)
				(type default)
			)
			(layer "B.Fab")
		)
		(fp_line
			(start -0.500126 1.598422)
			(end 0.500126 1.598422)
			(stroke
				(width 0.1)
				(type default)
			)
			(layer "B.Fab")
		)
		(pad "1" smd rect
			(at 0 0)
			(size 0.889 0.9906)
			(layers "B.Cu" "B.Mask" "B.Paste")
			(net "PVDDQ_GHJ")
		)
		(pad "2" smd rect
			(at 0 1.397)
			(size 0.889 0.9906)
			(layers "B.Cu" "B.Mask" "B.Paste")
			(net "GND")
		)
		(zone
			(layer "B.Cu")
			(hatch none 0.5)
			(connect_pads
				(clearance 0)
			)
			(min_thickness 0.25)
			(keepout
				(tracks allowed)
				(vias not_allowed)
				(pads allowed)
				(copperpour not_allowed)
				(footprints allowed)
			)
			(placement
				(enabled no)
				(sheetname "")
			)
			(fill
				(thermal_gap 0.5)
				(thermal_bridge_width 0.5)
				(island_removal_mode 0)
			)
			(polygon
				(pts
					(xy 108.8136 -8.6487) (xy 108.3056 -8.6487) (xy 108.3056 -7.6581) (xy 108.8136 -7.6581)
				)
			)
		)
		(zone
			(layer "B.Cu")
			(hatch none 0.5)
			(connect_pads
				(clearance 0)
			)
			(min_thickness 0.25)
			(keepout
				(tracks not_allowed)
				(vias allowed)
				(pads allowed)
				(copperpour not_allowed)
				(footprints allowed)
			)
			(placement
				(enabled no)
				(sheetname "")
			)
			(fill
				(thermal_gap 0.5)
				(thermal_bridge_width 0.5)
				(island_removal_mode 0)
			)
			(polygon
				(pts
					(xy 108.8136 -8.6487) (xy 108.3056 -8.6487) (xy 108.3056 -7.6581) (xy 108.8136 -7.6581)
				)
			)
		)
	)
)
